(kicad_pcb
	(version 20260206)
	(generator "pcbnew")
	(generator_version "10.0")
	(general
		(thickness 1.6)
		(legacy_teardrops no)
	)
	(paper "A4")
	(title_block
		(title "04192023_DAF0TMB3IC0_F0TG_MB_C_brd_V02_OCP.brd")
		(comment 1 "Grand Teton / footprints 6727-6734 of 8354")
	)
	(layers
		(0 "F.Cu" signal "TOP")
		(4 "In1.Cu" signal "GND")
		(6 "In2.Cu" signal "IN1")
		(8 "In3.Cu" signal "GND1")
		(10 "In4.Cu" signal "IN2")
		(12 "In5.Cu" signal "GND2")
		(14 "In6.Cu" signal "IN3")
		(16 "In7.Cu" signal "GND3")
		(18 "In8.Cu" signal "VCC")
		(20 "In9.Cu" signal "VCC1")
		(22 "In10.Cu" signal "GND4")
		(24 "In11.Cu" signal "IN4")
		(26 "In12.Cu" signal "GND5")
		(28 "In13.Cu" signal "IN5")
		(30 "In14.Cu" signal "GND6")
		(32 "In15.Cu" signal "IN6")
		(34 "In16.Cu" signal "GND7")
		(2 "B.Cu" signal "BOTTOM")
		(9 "F.Adhes" user "F.Adhesive")
		(11 "B.Adhes" user "B.Adhesive")
		(13 "F.Paste" user "Package Geometry/Pastemask Top")
		(15 "B.Paste" user "Package Geometry/Pastemask Bottom")
		(5 "F.SilkS" user "Ref Des/Silkscreen Top")
		(7 "B.SilkS" user "Ref Des/Silkscreen Bottom")
		(1 "F.Mask" user "Board Geometry/Soldermask Top")
		(3 "B.Mask" user "Board Geometry/Soldermask Bottom")
		(17 "Dwgs.User" user "User.Drawings")
		(19 "Cmts.User" user "User.Comments")
		(21 "Eco1.User" user "User.Eco1")
		(23 "Eco2.User" user "User.Eco2")
		(25 "Edge.Cuts" user "Board Geometry/Outline")
		(27 "Margin" user)
		(31 "F.CrtYd" user "Package Geometry/Place Bound Top")
		(29 "B.CrtYd" user "Package Geometry/Place Bound Bottom")
		(35 "F.Fab" user "Ref Des/Assembly Top")
		(33 "B.Fab" user "Ref Des/Assembly Bottom")
	)
	(footprint ""
		(layer "B.Cu")
		(at 113.705386 -250.257564)
		(property "Reference" "C2316"
			(at 0 0 0)
			(layer "B.SilkS")
			(hide yes)
			(effects
				(font
					(size 1.27 1.27)
				)
				(justify mirror)
			)
		)
		(property "Value" ""
			(at 0 0 0)
			(layer "B.Fab")
			(effects
				(font
					(size 1.27 1.27)
				)
				(justify mirror)
			)
		)
		(duplicate_pad_numbers_are_jumpers no)
		(fp_line
			(start -0.7874 -0.4064)
			(end -0.7874 0.4064)
			(stroke
				(width 0.1524)
				(type default)
			)
			(layer "B.SilkS")
		)
		(fp_line
			(start -0.7874 0.4064)
			(end 0.7874 0.4064)
			(stroke
				(width 0.1524)
				(type default)
			)
			(layer "B.SilkS")
		)
		(fp_line
			(start 0.7874 -0.4064)
			(end -0.7874 -0.4064)
			(stroke
				(width 0.1524)
				(type default)
			)
			(layer "B.SilkS")
		)
		(fp_line
			(start 0.7874 0.4064)
			(end 0.7874 -0.4064)
			(stroke
				(width 0.1524)
				(type default)
			)
			(layer "B.SilkS")
		)
		(fp_line
			(start -0.67945 -0.3048)
			(end -0.67945 0.3048)
			(stroke
				(width 0.1)
				(type default)
			)
			(layer "B.Fab")
		)
		(fp_line
			(start -0.67945 0.3048)
			(end -0.120396 0.3048)
			(stroke
				(width 0.1)
				(type default)
			)
			(layer "B.Fab")
		)
		(fp_line
			(start -0.12065 -0.3048)
			(end -0.67945 -0.3048)
			(stroke
				(width 0.1)
				(type default)
			)
			(layer "B.Fab")
		)
		(fp_line
			(start -0.12065 -0.2794)
			(end -0.12065 -0.3048)
			(stroke
				(width 0.1)
				(type default)
			)
			(layer "B.Fab")
		)
		(fp_line
			(start -0.120396 0.2794)
			(end 0.12065 0.2794)
			(stroke
				(width 0.1)
				(type default)
			)
			(layer "B.Fab")
		)
		(fp_line
			(start -0.120396 0.3048)
			(end -0.120396 0.2794)
			(stroke
				(width 0.1)
				(type default)
			)
			(layer "B.Fab")
		)
		(fp_line
			(start 0.12065 -0.305054)
			(end 0.12065 -0.2794)
			(stroke
				(width 0.1)
				(type default)
			)
			(layer "B.Fab")
		)
		(fp_line
			(start 0.12065 -0.2794)
			(end -0.12065 -0.2794)
			(stroke
				(width 0.1)
				(type default)
			)
			(layer "B.Fab")
		)
		(fp_line
			(start 0.12065 0.2794)
			(end 0.12065 0.3048)
			(stroke
				(width 0.1)
				(type default)
			)
			(layer "B.Fab")
		)
		(fp_line
			(start 0.12065 0.3048)
			(end 0.67945 0.3048)
			(stroke
				(width 0.1)
				(type default)
			)
			(layer "B.Fab")
		)
		(fp_line
			(start 0.67945 -0.305054)
			(end 0.12065 -0.305054)
			(stroke
				(width 0.1)
				(type default)
			)
			(layer "B.Fab")
		)
		(fp_line
			(start 0.67945 0.3048)
			(end 0.67945 -0.305054)
			(stroke
				(width 0.1)
				(type default)
			)
			(layer "B.Fab")
		)
		(pad "1" smd circle
			(at 0.40005 0 180)
			(size 0 0)
			(layers "B.Cu" "B.Mask" "B.Paste")
			(net "PVDDCR_CPU0_P1")
		)
		(pad "2" smd circle
			(at -0.40005 0 180)
			(size 0 0)
			(layers "B.Cu" "B.Mask" "B.Paste")
			(net "GND")
		)
	)
	(footprint ""
		(layer "B.Cu")
		(at 303.172622 -393.88288 -90)
		(property "Reference" "C539"
			(at 0 0 90)
			(layer "B.SilkS")
			(hide yes)
			(effects
				(font
					(size 1.27 1.27)
				)
				(justify mirror)
			)
		)
		(property "Value" ""
			(at 0 0 90)
			(layer "B.Fab")
			(effects
				(font
					(size 1.27 1.27)
				)
				(justify mirror)
			)
		)
		(duplicate_pad_numbers_are_jumpers no)
		(fp_line
			(start -0.299974 0.150114)
			(end 0.299974 0.150114)
			(stroke
				(width 0.1)
				(type default)
			)
			(layer "B.Fab")
		)
		(fp_line
			(start 0.299974 0.150114)
			(end 0.299974 -0.150114)
			(stroke
				(width 0.1)
				(type default)
			)
			(layer "B.Fab")
		)
		(fp_line
			(start -0.299974 -0.150114)
			(end -0.299974 0.150114)
			(stroke
				(width 0.1)
				(type default)
			)
			(layer "B.Fab")
		)
		(fp_line
			(start 0.299974 -0.150114)
			(end -0.299974 -0.150114)
			(stroke
				(width 0.1)
				(type default)
			)
			(layer "B.Fab")
		)
		(pad "1" smd rect
			(at 0.2667 0 90)
			(size 0.3048 0.381)
			(layers "B.Cu" "B.Mask" "B.Paste")
			(net "P0V9_CPU0_RT0_2A")
		)
		(pad "2" smd rect
			(at -0.2667 0 90)
			(size 0.3048 0.381)
			(layers "B.Cu" "B.Mask" "B.Paste")
			(net "GND")
		)
	)
	(footprint ""
		(layer "B.Cu")
		(at 323.417184 -396.150592 180)
		(property "Reference" "C566"
			(at 0 0 0)
			(layer "B.SilkS")
			(hide yes)
			(effects
				(font
					(size 1.27 1.27)
				)
				(justify mirror)
			)
		)
		(property "Value" ""
			(at 0 0 0)
			(layer "B.Fab")
			(effects
				(font
					(size 1.27 1.27)
				)
				(justify mirror)
			)
		)
		(duplicate_pad_numbers_are_jumpers no)
		(fp_line
			(start 0.299974 0.150114)
			(end 0.299974 -0.150114)
			(stroke
				(width 0.1)
				(type default)
			)
			(layer "B.Fab")
		)
		(fp_line
			(start 0.299974 -0.150114)
			(end -0.299974 -0.150114)
			(stroke
				(width 0.1)
				(type default)
			)
			(layer "B.Fab")
		)
		(fp_line
			(start -0.299974 0.150114)
			(end 0.299974 0.150114)
			(stroke
				(width 0.1)
				(type default)
			)
			(layer "B.Fab")
		)
		(fp_line
			(start -0.299974 -0.150114)
			(end -0.299974 0.150114)
			(stroke
				(width 0.1)
				(type default)
			)
			(layer "B.Fab")
		)
		(pad "1" smd rect
			(at 0.2667 0)
			(size 0.3048 0.381)
			(layers "B.Cu" "B.Mask" "B.Paste")
			(net "P0V9_CPU0_RT0_2A")
		)
		(pad "2" smd rect
			(at -0.2667 0)
			(size 0.3048 0.381)
			(layers "B.Cu" "B.Mask" "B.Paste")
			(net "GND")
		)
	)
	(footprint ""
		(layer "B.Cu")
		(at 13.65885 -403.855174 180)
		(property "Reference" "R6858"
			(at 0 0 0)
			(layer "B.SilkS")
			(hide yes)
			(effects
				(font
					(size 1.27 1.27)
				)
				(justify mirror)
			)
		)
		(property "Value" ""
			(at 0 0 0)
			(layer "B.Fab")
			(effects
				(font
					(size 1.27 1.27)
				)
				(justify mirror)
			)
		)
		(duplicate_pad_numbers_are_jumpers no)
		(fp_line
			(start 0.7874 0.4064)
			(end 0.7874 -0.4064)
			(stroke
				(width 0.1524)
				(type default)
			)
			(layer "B.SilkS")
		)
		(fp_line
			(start 0.7874 -0.4064)
			(end -0.7874 -0.4064)
			(stroke
				(width 0.1524)
				(type default)
			)
			(layer "B.SilkS")
		)
		(fp_line
			(start -0.7874 0.4064)
			(end 0.7874 0.4064)
			(stroke
				(width 0.1524)
				(type default)
			)
			(layer "B.SilkS")
		)
		(fp_line
			(start -0.7874 -0.4064)
			(end -0.7874 0.4064)
			(stroke
				(width 0.1524)
				(type default)
			)
			(layer "B.SilkS")
		)
		(fp_line
			(start 0.67945 0.3048)
			(end 0.67945 -0.305054)
			(stroke
				(width 0.1)
				(type default)
			)
			(layer "B.Fab")
		)
		(fp_line
			(start 0.67945 -0.305054)
			(end 0.12065 -0.305054)
			(stroke
				(width 0.1)
				(type default)
			)
			(layer "B.Fab")
		)
		(fp_line
			(start 0.12065 0.3048)
			(end 0.67945 0.3048)
			(stroke
				(width 0.1)
				(type default)
			)
			(layer "B.Fab")
		)
		(fp_line
			(start 0.12065 0.2794)
			(end 0.12065 0.3048)
			(stroke
				(width 0.1)
				(type default)
			)
			(layer "B.Fab")
		)
		(fp_line
			(start 0.12065 -0.2794)
			(end -0.12065 -0.2794)
			(stroke
				(width 0.1)
				(type default)
			)
			(layer "B.Fab")
		)
		(fp_line
			(start 0.12065 -0.305054)
			(end 0.12065 -0.2794)
			(stroke
				(width 0.1)
				(type default)
			)
			(layer "B.Fab")
		)
		(fp_line
			(start -0.120396 0.3048)
			(end -0.120396 0.2794)
			(stroke
				(width 0.1)
				(type default)
			)
			(layer "B.Fab")
		)
		(fp_line
			(start -0.120396 0.2794)
			(end 0.12065 0.2794)
			(stroke
				(width 0.1)
				(type default)
			)
			(layer "B.Fab")
		)
		(fp_line
			(start -0.12065 -0.2794)
			(end -0.12065 -0.3048)
			(stroke
				(width 0.1)
				(type default)
			)
			(layer "B.Fab")
		)
		(fp_line
			(start -0.12065 -0.3048)
			(end -0.67945 -0.3048)
			(stroke
				(width 0.1)
				(type default)
			)
			(layer "B.Fab")
		)
		(fp_line
			(start -0.67945 0.3048)
			(end -0.120396 0.3048)
			(stroke
				(width 0.1)
				(type default)
			)
			(layer "B.Fab")
		)
		(fp_line
			(start -0.67945 -0.3048)
			(end -0.67945 0.3048)
			(stroke
				(width 0.1)
				(type default)
			)
			(layer "B.Fab")
		)
		(pad "1" smd circle
			(at 0.40005 0)
			(size 0 0)
			(layers "B.Cu" "B.Mask" "B.Paste")
			(net "SMB_VR_3V3STBY_SCL")
		)
		(pad "2" smd circle
			(at -0.40005 0)
			(size 0 0)
			(layers "B.Cu" "B.Mask" "B.Paste")
			(net "P0V9_RETIMER_CPU1_PMSCL")
		)
	)
	(footprint ""
		(layer "B.Cu")
		(at 356.711758 -271.395952)
		(property "Reference" "C2209"
			(at 0 0 0)
			(layer "B.SilkS")
			(hide yes)
			(effects
				(font
					(size 1.27 1.27)
				)
				(justify mirror)
			)
		)
		(property "Value" ""
			(at 0 0 0)
			(layer "B.Fab")
			(effects
				(font
					(size 1.27 1.27)
				)
				(justify mirror)
			)
		)
		(duplicate_pad_numbers_are_jumpers no)
		(fp_line
			(start -0.7874 -0.4064)
			(end -0.7874 0.4064)
			(stroke
				(width 0.1524)
				(type default)
			)
			(layer "B.SilkS")
		)
		(fp_line
			(start -0.7874 0.4064)
			(end 0.7874 0.4064)
			(stroke
				(width 0.1524)
				(type default)
			)
			(layer "B.SilkS")
		)
		(fp_line
			(start 0.7874 -0.4064)
			(end -0.7874 -0.4064)
			(stroke
				(width 0.1524)
				(type default)
			)
			(layer "B.SilkS")
		)
		(fp_line
			(start 0.7874 0.4064)
			(end 0.7874 -0.4064)
			(stroke
				(width 0.1524)
				(type default)
			)
			(layer "B.SilkS")
		)
		(fp_line
			(start -0.67945 -0.3048)
			(end -0.67945 0.3048)
			(stroke
				(width 0.1)
				(type default)
			)
			(layer "B.Fab")
		)
		(fp_line
			(start -0.67945 0.3048)
			(end -0.120396 0.3048)
			(stroke
				(width 0.1)
				(type default)
			)
			(layer "B.Fab")
		)
		(fp_line
			(start -0.12065 -0.3048)
			(end -0.67945 -0.3048)
			(stroke
				(width 0.1)
				(type default)
			)
			(layer "B.Fab")
		)
		(fp_line
			(start -0.12065 -0.2794)
			(end -0.12065 -0.3048)
			(stroke
				(width 0.1)
				(type default)
			)
			(layer "B.Fab")
		)
		(fp_line
			(start -0.120396 0.2794)
			(end 0.12065 0.2794)
			(stroke
				(width 0.1)
				(type default)
			)
			(layer "B.Fab")
		)
		(fp_line
			(start -0.120396 0.3048)
			(end -0.120396 0.2794)
			(stroke
				(width 0.1)
				(type default)
			)
			(layer "B.Fab")
		)
		(fp_line
			(start 0.12065 -0.305054)
			(end 0.12065 -0.2794)
			(stroke
				(width 0.1)
				(type default)
			)
			(layer "B.Fab")
		)
		(fp_line
			(start 0.12065 -0.2794)
			(end -0.12065 -0.2794)
			(stroke
				(width 0.1)
				(type default)
			)
			(layer "B.Fab")
		)
		(fp_line
			(start 0.12065 0.2794)
			(end 0.12065 0.3048)
			(stroke
				(width 0.1)
				(type default)
			)
			(layer "B.Fab")
		)
		(fp_line
			(start 0.12065 0.3048)
			(end 0.67945 0.3048)
			(stroke
				(width 0.1)
				(type default)
			)
			(layer "B.Fab")
		)
		(fp_line
			(start 0.67945 -0.305054)
			(end 0.12065 -0.305054)
			(stroke
				(width 0.1)
				(type default)
			)
			(layer "B.Fab")
		)
		(fp_line
			(start 0.67945 0.3048)
			(end 0.67945 -0.305054)
			(stroke
				(width 0.1)
				(type default)
			)
			(layer "B.Fab")
		)
		(pad "1" smd circle
			(at 0.40005 0 180)
			(size 0 0)
			(layers "B.Cu" "B.Mask" "B.Paste")
			(net "PVDDCR_CPU1_P0")
		)
		(pad "2" smd circle
			(at -0.40005 0 180)
			(size 0 0)
			(layers "B.Cu" "B.Mask" "B.Paste")
			(net "GND")
		)
	)
	(footprint ""
		(layer "B.Cu")
		(at 188.138562 -144.58823 180)
		(property "Reference" "C8007"
			(at 0 0 0)
			(layer "B.SilkS")
			(hide yes)
			(effects
				(font
					(size 1.27 1.27)
				)
				(justify mirror)
			)
		)
		(property "Value" ""
			(at 0 0 0)
			(layer "B.Fab")
			(effects
				(font
					(size 1.27 1.27)
				)
				(justify mirror)
			)
		)
		(duplicate_pad_numbers_are_jumpers no)
		(fp_line
			(start 0.7874 0.4064)
			(end 0.7874 -0.4064)
			(stroke
				(width 0.1524)
				(type default)
			)
			(layer "B.SilkS")
		)
		(fp_line
			(start 0.7874 -0.4064)
			(end -0.7874 -0.4064)
			(stroke
				(width 0.1524)
				(type default)
			)
			(layer "B.SilkS")
		)
		(fp_line
			(start -0.7874 0.4064)
			(end 0.7874 0.4064)
			(stroke
				(width 0.1524)
				(type default)
			)
			(layer "B.SilkS")
		)
		(fp_line
			(start -0.7874 -0.4064)
			(end -0.7874 0.4064)
			(stroke
				(width 0.1524)
				(type default)
			)
			(layer "B.SilkS")
		)
		(fp_line
			(start 0.67945 0.3048)
			(end 0.67945 -0.305054)
			(stroke
				(width 0.1)
				(type default)
			)
			(layer "B.Fab")
		)
		(fp_line
			(start 0.67945 -0.305054)
			(end 0.12065 -0.305054)
			(stroke
				(width 0.1)
				(type default)
			)
			(layer "B.Fab")
		)
		(fp_line
			(start 0.12065 0.3048)
			(end 0.67945 0.3048)
			(stroke
				(width 0.1)
				(type default)
			)
			(layer "B.Fab")
		)
		(fp_line
			(start 0.12065 0.2794)
			(end 0.12065 0.3048)
			(stroke
				(width 0.1)
				(type default)
			)
			(layer "B.Fab")
		)
		(fp_line
			(start 0.12065 -0.2794)
			(end -0.12065 -0.2794)
			(stroke
				(width 0.1)
				(type default)
			)
			(layer "B.Fab")
		)
		(fp_line
			(start 0.12065 -0.305054)
			(end 0.12065 -0.2794)
			(stroke
				(width 0.1)
				(type default)
			)
			(layer "B.Fab")
		)
		(fp_line
			(start -0.120396 0.3048)
			(end -0.120396 0.2794)
			(stroke
				(width 0.1)
				(type default)
			)
			(layer "B.Fab")
		)
		(fp_line
			(start -0.120396 0.2794)
			(end 0.12065 0.2794)
			(stroke
				(width 0.1)
				(type default)
			)
			(layer "B.Fab")
		)
		(fp_line
			(start -0.12065 -0.2794)
			(end -0.12065 -0.3048)
			(stroke
				(width 0.1)
				(type default)
			)
			(layer "B.Fab")
		)
		(fp_line
			(start -0.12065 -0.3048)
			(end -0.67945 -0.3048)
			(stroke
				(width 0.1)
				(type default)
			)
			(layer "B.Fab")
		)
		(fp_line
			(start -0.67945 0.3048)
			(end -0.120396 0.3048)
			(stroke
				(width 0.1)
				(type default)
			)
			(layer "B.Fab")
		)
		(fp_line
			(start -0.67945 -0.3048)
			(end -0.67945 0.3048)
			(stroke
				(width 0.1)
				(type default)
			)
			(layer "B.Fab")
		)
		(pad "1" smd circle
			(at 0.40005 0)
			(size 0 0)
			(layers "B.Cu" "B.Mask" "B.Paste")
			(net "P1V8_AUX")
		)
		(pad "2" smd circle
			(at -0.40005 0)
			(size 0 0)
			(layers "B.Cu" "B.Mask" "B.Paste")
			(net "GND")
		)
	)
	(footprint ""
		(layer "B.Cu")
		(at 412.618936 -398.942052 90)
		(property "Reference" "C671"
			(at 0 0 90)
			(layer "B.SilkS")
			(hide yes)
			(effects
				(font
					(size 1.27 1.27)
				)
				(justify mirror)
			)
		)
		(property "Value" ""
			(at 0 0 90)
			(layer "B.Fab")
			(effects
				(font
					(size 1.27 1.27)
				)
				(justify mirror)
			)
		)
		(duplicate_pad_numbers_are_jumpers no)
		(fp_line
			(start 0.7874 -0.4064)
			(end -0.7874 -0.4064)
			(stroke
				(width 0.1524)
				(type default)
			)
			(layer "B.SilkS")
		)
		(fp_line
			(start -0.7874 -0.4064)
			(end -0.7874 0.4064)
			(stroke
				(width 0.1524)
				(type default)
			)
			(layer "B.SilkS")
		)
		(fp_line
			(start 0.7874 0.4064)
			(end 0.7874 -0.4064)
			(stroke
				(width 0.1524)
				(type default)
			)
			(layer "B.SilkS")
		)
		(fp_line
			(start -0.7874 0.4064)
			(end 0.7874 0.4064)
			(stroke
				(width 0.1524)
				(type default)
			)
			(layer "B.SilkS")
		)
		(fp_line
			(start 0.67945 -0.305054)
			(end 0.12065 -0.305054)
			(stroke
				(width 0.1)
				(type default)
			)
			(layer "B.Fab")
		)
		(fp_line
			(start 0.12065 -0.305054)
			(end 0.12065 -0.2794)
			(stroke
				(width 0.1)
				(type default)
			)
			(layer "B.Fab")
		)
		(fp_line
			(start -0.12065 -0.3048)
			(end -0.67945 -0.3048)
			(stroke
				(width 0.1)
				(type default)
			)
			(layer "B.Fab")
		)
		(fp_line
			(start -0.67945 -0.3048)
			(end -0.67945 0.3048)
			(stroke
				(width 0.1)
				(type default)
			)
			(layer "B.Fab")
		)
		(fp_line
			(start 0.12065 -0.2794)
			(end -0.12065 -0.2794)
			(stroke
				(width 0.1)
				(type default)
			)
			(layer "B.Fab")
		)
		(fp_line
			(start -0.12065 -0.2794)
			(end -0.12065 -0.3048)
			(stroke
				(width 0.1)
				(type default)
			)
			(layer "B.Fab")
		)
		(fp_line
			(start 0.12065 0.2794)
			(end 0.12065 0.3048)
			(stroke
				(width 0.1)
				(type default)
			)
			(layer "B.Fab")
		)
		(fp_line
			(start -0.120396 0.2794)
			(end 0.12065 0.2794)
			(stroke
				(width 0.1)
				(type default)
			)
			(layer "B.Fab")
		)
		(fp_line
			(start 0.67945 0.3048)
			(end 0.67945 -0.305054)
			(stroke
				(width 0.1)
				(type default)
			)
			(layer "B.Fab")
		)
		(fp_line
			(start 0.12065 0.3048)
			(end 0.67945 0.3048)
			(stroke
				(width 0.1)
				(type default)
			)
			(layer "B.Fab")
		)
		(fp_line
			(start -0.120396 0.3048)
			(end -0.120396 0.2794)
			(stroke
				(width 0.1)
				(type default)
			)
			(layer "B.Fab")
		)
		(fp_line
			(start -0.67945 0.3048)
			(end -0.120396 0.3048)
			(stroke
				(width 0.1)
				(type default)
			)
			(layer "B.Fab")
		)
		(pad "1" smd circle
			(at 0.40005 0 270)
			(size 0 0)
			(layers "B.Cu" "B.Mask" "B.Paste")
			(net "P1V8_CPU0_RT2_1A")
		)
		(pad "2" smd circle
			(at -0.40005 0 270)
			(size 0 0)
			(layers "B.Cu" "B.Mask" "B.Paste")
			(net "GND")
		)
	)
	(footprint ""
		(layer "B.Cu")
		(at 229.8446 -341.884 180)
		(property "Reference" "R6754"
			(at 0 0 0)
			(layer "B.SilkS")
			(hide yes)
			(effects
				(font
					(size 1.27 1.27)
				)
				(justify mirror)
			)
		)
		(property "Value" ""
			(at 0 0 0)
			(layer "B.Fab")
			(effects
				(font
					(size 1.27 1.27)
				)
				(justify mirror)
			)
		)
		(duplicate_pad_numbers_are_jumpers no)
		(fp_line
			(start 0.32512 0.175006)
			(end 0.32512 -0.175006)
			(stroke
				(width 0.1)
				(type default)
			)
			(layer "B.Fab")
		)
		(fp_line
			(start 0.32512 -0.175006)
			(end -0.32512 -0.175006)
			(stroke
				(width 0.1)
				(type default)
			)
			(layer "B.Fab")
		)
		(fp_line
			(start -0.32512 0.175006)
			(end 0.32512 0.175006)
			(stroke
				(width 0.1)
				(type default)
			)
			(layer "B.Fab")
		)
		(fp_line
			(start -0.32512 -0.175006)
			(end -0.32512 0.175006)
			(stroke
				(width 0.1)
				(type default)
			)
			(layer "B.Fab")
		)
		(pad "1" smd rect
			(at 0.2667 0)
			(size 0.3048 0.381)
			(layers "B.Cu" "B.Mask" "B.Paste")
			(net "SMB_RT_CPU0_P0_SDA")
		)
		(pad "2" smd rect
			(at -0.2667 0 180)
			(size 0.3048 0.381)
			(layers "B.Cu" "B.Mask" "B.Paste")
			(net "SMB_RT_CPU0_P0_R_SDA")
		)
	)
)
